# BASEBOARD_FAB2 (Tioga Pass) — schematic netlist excerpt (pin names and nets, part order shuffled) for the footprints in the layout excerpt that follows; sources: Cadence DE-HDL packaged netlist, KiCad conversion of Wiwynn_Tioga_Pass_MB.brd

L7G2  IND-120NH-30-GP  pkg DISCRET-GB2  page 216 : S = VR_PVDDQ_ABC_PH2_SW ; F = PVDDQ_ABC
RT22  1R3F-GP  1%  pkg RCL_GP  page 224 : \1\ = VR_PVDDQ_GHJ_PH2_SW_RC ; \2\ = GND

(kicad_pcb
	(version 20260206)
	(generator "pcbnew")
	(generator_version "10.0")
	(general
		(thickness 1.6)
		(legacy_teardrops no)
	)
	(paper "A4")
	(title_block
		(title "Wiwynn_Tioga_Pass_MB.brd")
		(comment 1 "Tioga Pass / footprints 1797-1798 of 4770")
	)
	(layers
		(0 "F.Cu" signal "TOP")
		(4 "In1.Cu" signal "L2GND")
		(6 "In2.Cu" signal "L3")
		(8 "In3.Cu" signal "L4GND")
		(10 "In4.Cu" signal "L5")
		(12 "In5.Cu" signal "L6GND")
		(14 "In6.Cu" signal "L7VCC")
		(16 "In7.Cu" signal "L8VCC")
		(18 "In8.Cu" signal "L9GND")
		(20 "In9.Cu" signal "L10")
		(22 "In10.Cu" signal "L11GND")
		(24 "In11.Cu" signal "L12")
		(26 "In12.Cu" signal "L13GND")
		(2 "B.Cu" signal "BOTTOM")
		(9 "F.Adhes" user "F.Adhesive")
		(11 "B.Adhes" user "B.Adhesive")
		(13 "F.Paste" user "Package Geometry/Pastemask Top")
		(15 "B.Paste" user "Package Geometry/Pastemask Bottom")
		(5 "F.SilkS" user "Ref Des/Silkscreen Top")
		(7 "B.SilkS" user "Ref Des/Silkscreen Bottom")
		(1 "F.Mask" user "Board Geometry/Soldermask Top")
		(3 "B.Mask" user "Board Geometry/Soldermask Bottom")
		(17 "Dwgs.User" user "User.Drawings")
		(19 "Cmts.User" user "User.Comments")
		(21 "Eco1.User" user "User.Eco1")
		(23 "Eco2.User" user "User.Eco2")
		(25 "Edge.Cuts" user "Board Geometry/Outline")
		(27 "Margin" user)
		(31 "F.CrtYd" user "Package Geometry/Place Bound Top")
		(29 "B.CrtYd" user "Package Geometry/Place Bound Bottom")
		(35 "F.Fab" user "Ref Des/Assembly Top")
		(33 "B.Fab" user "Ref Des/Assembly Bottom")
	)
	(footprint ""
		(layer "F.Cu")
		(at 341.049864 1.898904 180)
		(property "Reference" "L7G2"
			(at 3.378708 -4.251706 180)
			(unlocked yes)
			(layer "F.SilkS")
			(effects
				(font
					(size 0.4064 0.254)
					(thickness 0.1524)
				)
			)
		)
		(property "Value" ""
			(at 0 0 180)
			(layer "F.Fab")
			(effects
				(font
					(size 1.27 1.27)
				)
			)
		)
		(duplicate_pad_numbers_are_jumpers no)
		(fp_line
			(start 8.3693 3.199892)
			(end -1.1303 3.199892)
			(stroke
				(width 0.1524)
				(type default)
			)
			(layer "F.SilkS")
		)
		(fp_line
			(start 8.3693 1.6637)
			(end 8.3693 3.199892)
			(stroke
				(width 0.1524)
				(type default)
			)
			(layer "F.SilkS")
		)
		(fp_line
			(start 8.3693 -3.199892)
			(end 8.3693 -1.6637)
			(stroke
				(width 0.1524)
				(type default)
			)
			(layer "F.SilkS")
		)
		(fp_line
			(start -1.1303 3.199892)
			(end -1.1303 1.6637)
			(stroke
				(width 0.1524)
				(type default)
			)
			(layer "F.SilkS")
		)
		(fp_line
			(start -1.1303 -1.6637)
			(end -1.1303 -3.199892)
			(stroke
				(width 0.1524)
				(type default)
			)
			(layer "F.SilkS")
		)
		(fp_line
			(start -1.1303 -3.199892)
			(end 8.3693 -3.199892)
			(stroke
				(width 0.1524)
				(type default)
			)
			(layer "F.SilkS")
		)
		(fp_rect
			(start -1.1303 3.199892)
			(end 8.3693 -3.199892)
			(stroke
				(width 0)
				(type default)
			)
			(fill no)
			(layer "F.CrtYd")
		)
		(fp_line
			(start 8.3693 3.199892)
			(end -1.1303 3.199892)
			(stroke
				(width 0.1)
				(type default)
			)
			(layer "F.Fab")
		)
		(fp_line
			(start 8.3693 -3.199892)
			(end 8.3693 3.199892)
			(stroke
				(width 0.1)
				(type default)
			)
			(layer "F.Fab")
		)
		(fp_line
			(start -1.1303 3.199892)
			(end -1.1303 -3.199892)
			(stroke
				(width 0.1)
				(type default)
			)
			(layer "F.Fab")
		)
		(fp_line
			(start -1.1303 -3.199892)
			(end 8.3693 -3.199892)
			(stroke
				(width 0.1)
				(type default)
			)
			(layer "F.Fab")
		)
		(pad "1" smd rect
			(at 0 0 180)
			(size 3.683 2.667)
			(layers "F.Cu" "F.Mask" "F.Paste")
			(net "VR_PVDDQ_ABC_PH2_SW")
		)
		(pad "2" smd rect
			(at 7.239 0 180)
			(size 3.683 2.667)
			(layers "F.Cu" "F.Mask" "F.Paste")
			(net "PVDDQ_ABC")
		)
	)
	(footprint ""
		(layer "F.Cu")
		(at 6.843522 -13.302996 -90)
		(property "Reference" "RT22"
			(at 0 0 270)
			(layer "F.SilkS")
			(hide yes)
			(effects
				(font
					(size 1.27 1.27)
				)
			)
		)
		(property "Value" "*"
			(at -0.0254 -2.6289 270)
			(unlocked yes)
			(layer "F.Fab")
			(hide yes)
			(effects
				(font
					(size 1.27 1.016)
					(thickness 0.1524)
				)
			)
		)
		(property "Device Type" "1R3F-GP_RCL_GP-1R3F-GP,64.1R00A"
			(at -0.0254 -4.1529 270)
			(unlocked yes)
			(layer "F.Fab")
			(hide yes)
			(effects
				(font
					(size 1.27 1.016)
					(thickness 0.1524)
				)
			)
		)
		(duplicate_pad_numbers_are_jumpers no)
		(fp_line
			(start -0.4826 0)
			(end -0.2032 0)
			(stroke
				(width 0.2032)
				(type default)
			)
			(layer "F.SilkS")
		)
		(fp_line
			(start 0.2032 0)
			(end 0.4826 0)
			(stroke
				(width 0.2032)
				(type default)
			)
			(layer "F.SilkS")
		)
		(fp_rect
			(start -0.5842 1.3335)
			(end 0.5842 -1.3335)
			(stroke
				(width 0)
				(type default)
			)
			(fill no)
			(layer "F.CrtYd")
		)
		(fp_rect
			(start -0.5842 1.3335)
			(end 0.5842 -1.3335)
			(stroke
				(width 0)
				(type default)
			)
			(fill no)
			(layer "F.Fab")
		)
		(pad "1" smd custom
			(at 0 -0.762 270)
			(size 0.2159 0.2159)
			(layers "F.Cu" "F.Mask" "F.Paste")
			(net "VR_PVDDQ_GHJ_PH2_SW_RC")
			(options
				(clearance outline)
				(anchor circle)
			)
			(primitives
				(gr_poly
					(pts
						(arc
							(start -0.3302 -0.4318)
							(mid -0.402042 -0.402042)
							(end -0.4318 -0.3302)
						)
						(arc
							(start -0.4318 0.3302)
							(mid -0.402042 0.402042)
							(end -0.3302 0.4318)
						)
						(arc
							(start 0.3302 0.4318)
							(mid 0.402042 0.402042)
							(end 0.4318 0.3302)
						)
						(arc
							(start 0.4318 -0.3302)
							(mid 0.402042 -0.402042)
							(end 0.3302 -0.4318)
						)
					)
					(width 0)
					(fill yes)
				)
			)
		)
		(pad "2" smd custom
			(at 0 0.762 270)
			(size 0.2159 0.2159)
			(layers "F.Cu" "F.Mask" "F.Paste")
			(net "GND")
			(options
				(clearance outline)
				(anchor circle)
			)
			(primitives
				(gr_poly
					(pts
						(arc
							(start -0.3302 -0.4318)
							(mid -0.402042 -0.402042)
							(end -0.4318 -0.3302)
						)
						(arc
							(start -0.4318 0.3302)
							(mid -0.402042 0.402042)
							(end -0.3302 0.4318)
						)
						(arc
							(start 0.3302 0.4318)
							(mid 0.402042 0.402042)
							(end 0.4318 0.3302)
						)
						(arc
							(start 0.4318 -0.3302)
							(mid 0.402042 -0.402042)
							(end 0.3302 -0.4318)
						)
					)
					(width 0)
					(fill yes)
				)
			)
		)
	)
)
